(kicad_pcb
	(version 20260206)
	(generator "pcbnew")
	(generator_version "10.0")
	(general
		(thickness 1.6)
		(legacy_teardrops no)
	)
	(paper "A4")
	(title_block
		(title "netronome-mezz — pcbd0082-001_rev01_jul9_a.brd")
		(comment 1 "Open CloudServer (Microsoft) / footprints 210-219 of 714")
	)
	(layers
		(0 "F.Cu" signal "TOP")
		(4 "In1.Cu" signal "02_GND")
		(6 "In2.Cu" signal "03_SIG")
		(8 "In3.Cu" signal "04_SIG")
		(10 "In4.Cu" signal "05_GND")
		(12 "In5.Cu" signal "06_PWR1")
		(14 "In6.Cu" signal "07_SIG")
		(16 "In7.Cu" signal "08_SIG")
		(18 "In8.Cu" signal "09_GND")
		(2 "B.Cu" signal "BOTTOM")
		(9 "F.Adhes" user "F.Adhesive")
		(11 "B.Adhes" user "B.Adhesive")
		(13 "F.Paste" user "Package Geometry/Pastemask Top")
		(15 "B.Paste" user "Package Geometry/Pastemask Bottom")
		(5 "F.SilkS" user "Ref Des/Silkscreen Top")
		(7 "B.SilkS" user "Ref Des/Silkscreen Bottom")
		(1 "F.Mask" user "Board Geometry/Soldermask Top")
		(3 "B.Mask" user "Board Geometry/Soldermask Bottom")
		(17 "Dwgs.User" user "User.Drawings")
		(19 "Cmts.User" user "User.Comments")
		(21 "Eco1.User" user "User.Eco1")
		(23 "Eco2.User" user "User.Eco2")
		(25 "Edge.Cuts" user "Board Geometry/Outline")
		(27 "Margin" user)
		(31 "F.CrtYd" user "Package Geometry/Place Bound Top")
		(29 "B.CrtYd" user "Package Geometry/Place Bound Bottom")
		(35 "F.Fab" user "Ref Des/Assembly Top")
		(33 "B.Fab" user "Ref Des/Assembly Bottom")
		(45 "User.4" user "COMPVAL_TYPE_BOTTOM")
	)
	(footprint ""
		(layer "F.Cu")
		(at 84.201 37.973)
		(property "Reference" "R105"
			(at 0.381 -0.10033 0)
			(unlocked yes)
			(layer "F.SilkS")
			(effects
				(font
					(size 0.7874 0.5842)
					(thickness 0.127)
				)
				(justify left)
			)
		)
		(property "Value" "4.75K"
			(at -0.148158 1.3462 90)
			(unlocked yes)
			(layer "F.Fab")
			(hide yes)
			(effects
				(font
					(size 1.27 0.9652)
					(thickness 0.000001)
				)
				(justify left)
			)
		)
		(property "Device Type" "REST4024"
			(at -0.148158 1.3462 90)
			(unlocked yes)
			(layer "F.Fab")
			(hide yes)
			(effects
				(font
					(size 1.27 0.9652)
					(thickness 0.000001)
				)
				(justify left)
			)
		)
		(duplicate_pad_numbers_are_jumpers no)
		(fp_poly
			(pts
				(xy 0.635 1.0668) (xy 0.635 -1.0668) (xy -0.635 -1.0668) (xy -0.635 1.0668)
			)
			(stroke
				(width 0)
				(type default)
			)
			(fill no)
			(layer "F.CrtYd")
		)
		(fp_line
			(start -0.254 -0.508)
			(end 0.254 -0.508)
			(stroke
				(width 0.0254)
				(type default)
			)
			(layer "F.Fab")
		)
		(fp_line
			(start -0.254 0.508)
			(end -0.254 -0.508)
			(stroke
				(width 0.0254)
				(type default)
			)
			(layer "F.Fab")
		)
		(fp_line
			(start 0.254 -0.508)
			(end 0.254 0.508)
			(stroke
				(width 0.0254)
				(type default)
			)
			(layer "F.Fab")
		)
		(fp_line
			(start 0.254 0.508)
			(end -0.254 0.508)
			(stroke
				(width 0.0254)
				(type default)
			)
			(layer "F.Fab")
		)
		(pad "1" smd rect
			(at 0 -0.4191)
			(size 0.508 0.5334)
			(layers "F.Cu" "F.Mask" "F.Paste")
			(net "GND")
		)
		(pad "2" smd rect
			(at 0 0.4191)
			(size 0.508 0.5334)
			(layers "F.Cu" "F.Mask" "F.Paste")
			(net "VDDQ_VTT_EN")
		)
		(zone
			(layer "F.Cu")
			(hatch none 0.5)
			(connect_pads
				(clearance 0)
			)
			(min_thickness 0.25)
			(keepout
				(tracks not_allowed)
				(vias allowed)
				(pads allowed)
				(copperpour not_allowed)
				(footprints allowed)
			)
			(placement
				(enabled no)
				(sheetname "")
			)
			(fill
				(thermal_gap 0.5)
				(thermal_bridge_width 0.5)
				(island_removal_mode 0)
			)
			(polygon
				(pts
					(xy 84.2264 37.9476) (xy 84.2264 37.9984) (xy 84.1756 37.9984) (xy 84.1756 37.9476)
				)
			)
		)
	)
	(footprint ""
		(layer "F.Cu")
		(at 21.5265 1.397 -90)
		(property "Reference" "R384"
			(at -0.381 -0.09017 90)
			(unlocked yes)
			(layer "F.SilkS")
			(effects
				(font
					(size 0.7874 0.5842)
					(thickness 0.127)
				)
				(justify left)
			)
		)
		(property "Value" "0"
			(at -0.148158 1.3462 0)
			(unlocked yes)
			(layer "F.Fab")
			(hide yes)
			(effects
				(font
					(size 1.27 0.9652)
					(thickness 0.000001)
				)
				(justify left)
			)
		)
		(property "Device Type" "REST1111"
			(at -0.148158 1.3462 0)
			(unlocked yes)
			(layer "F.Fab")
			(hide yes)
			(effects
				(font
					(size 1.27 0.9652)
					(thickness 0.000001)
				)
				(justify left)
			)
		)
		(duplicate_pad_numbers_are_jumpers no)
		(fp_poly
			(pts
				(xy 0.635 1.0668) (xy 0.635 -1.0668) (xy -0.635 -1.0668) (xy -0.635 1.0668)
			)
			(stroke
				(width 0)
				(type default)
			)
			(fill no)
			(layer "F.CrtYd")
		)
		(fp_line
			(start -0.254 0.508)
			(end -0.254 -0.508)
			(stroke
				(width 0.0254)
				(type default)
			)
			(layer "F.Fab")
		)
		(fp_line
			(start 0.254 0.508)
			(end -0.254 0.508)
			(stroke
				(width 0.0254)
				(type default)
			)
			(layer "F.Fab")
		)
		(fp_line
			(start -0.254 -0.508)
			(end 0.254 -0.508)
			(stroke
				(width 0.0254)
				(type default)
			)
			(layer "F.Fab")
		)
		(fp_line
			(start 0.254 -0.508)
			(end 0.254 0.508)
			(stroke
				(width 0.0254)
				(type default)
			)
			(layer "F.Fab")
		)
		(pad "1" smd rect
			(at 0 -0.4191 270)
			(size 0.508 0.5334)
			(layers "F.Cu" "F.Mask" "F.Paste")
			(net "NFP_PCIE0_WAKE_L")
		)
		(pad "2" smd rect
			(at 0 0.4191 270)
			(size 0.508 0.5334)
			(layers "F.Cu" "F.Mask" "F.Paste")
			(net "MUX_NFP_PCIE0_WAKE_L")
		)
		(zone
			(layer "F.Cu")
			(hatch none 0.5)
			(connect_pads
				(clearance 0)
			)
			(min_thickness 0.25)
			(keepout
				(tracks not_allowed)
				(vias allowed)
				(pads allowed)
				(copperpour not_allowed)
				(footprints allowed)
			)
			(placement
				(enabled no)
				(sheetname "")
			)
			(fill
				(thermal_gap 0.5)
				(thermal_bridge_width 0.5)
				(island_removal_mode 0)
			)
			(polygon
				(pts
					(xy 21.5519 1.4224) (xy 21.5011 1.4224) (xy 21.5011 1.3716) (xy 21.5519 1.3716)
				)
			)
		)
	)
	(footprint ""
		(layer "F.Cu")
		(at 74.3712 43.942 -90)
		(property "Reference" "TP54"
			(at 0.889 1.75133 90)
			(unlocked yes)
			(layer "F.SilkS")
			(effects
				(font
					(size 0.7874 0.5842)
					(thickness 0.127)
				)
				(justify left)
			)
		)
		(property "Value" "*"
			(at -0.4826 -0.14732 270)
			(unlocked yes)
			(layer "F.Fab")
			(hide yes)
			(effects
				(font
					(size 1.27 0.9652)
					(thickness 0.000001)
				)
				(justify left)
			)
		)
		(property "Device Type" "TP_SMALL"
			(at -0.4826 -0.14732 270)
			(unlocked yes)
			(layer "F.Fab")
			(hide yes)
			(effects
				(font
					(size 1.27 0.9652)
					(thickness 0.000001)
				)
				(justify left)
			)
		)
		(duplicate_pad_numbers_are_jumpers no)
		(fp_line
			(start -0.8636 0.8636)
			(end 0.8636 0.8636)
			(stroke
				(width 0.1524)
				(type default)
			)
			(layer "F.SilkS")
		)
		(fp_line
			(start 0.8636 0.8636)
			(end 0.8636 -0.8636)
			(stroke
				(width 0.1524)
				(type default)
			)
			(layer "F.SilkS")
		)
		(fp_line
			(start -0.8636 -0.8636)
			(end -0.8636 0.8636)
			(stroke
				(width 0.1524)
				(type default)
			)
			(layer "F.SilkS")
		)
		(fp_line
			(start 0.8636 -0.8636)
			(end -0.8636 -0.8636)
			(stroke
				(width 0.1524)
				(type default)
			)
			(layer "F.SilkS")
		)
		(fp_poly
			(pts
				(xy -0.635 -0.635) (xy -0.635 0.635) (xy 0.635 0.635) (xy 0.635 -0.635)
			)
			(stroke
				(width 0)
				(type default)
			)
			(fill no)
			(layer "F.CrtYd")
		)
		(pad "1" smd rect
			(at 0 0 270)
			(size 1.27 1.27)
			(layers "F.Cu" "F.Mask" "F.Paste")
			(net "DDR_VDDQ")
		)
	)
	(footprint ""
		(layer "F.Cu")
		(at 26.162 17.272)
		(property "Reference" "TP58"
			(at -2.032 -1.49733 0)
			(unlocked yes)
			(layer "F.SilkS")
			(effects
				(font
					(size 0.7874 0.5842)
					(thickness 0.127)
				)
				(justify left)
			)
		)
		(property "Value" "*"
			(at -0.4826 -0.14732 0)
			(unlocked yes)
			(layer "F.Fab")
			(hide yes)
			(effects
				(font
					(size 1.27 0.9652)
					(thickness 0.000001)
				)
				(justify left)
			)
		)
		(property "Device Type" "TP_SMALL"
			(at -0.4826 -0.14732 0)
			(unlocked yes)
			(layer "F.Fab")
			(hide yes)
			(effects
				(font
					(size 1.27 0.9652)
					(thickness 0.000001)
				)
				(justify left)
			)
		)
		(duplicate_pad_numbers_are_jumpers no)
		(fp_line
			(start -0.8636 -0.8636)
			(end -0.8636 0.8636)
			(stroke
				(width 0.1524)
				(type default)
			)
			(layer "F.SilkS")
		)
		(fp_line
			(start -0.8636 0.8636)
			(end 0.8636 0.8636)
			(stroke
				(width 0.1524)
				(type default)
			)
			(layer "F.SilkS")
		)
		(fp_line
			(start 0.8636 -0.8636)
			(end -0.8636 -0.8636)
			(stroke
				(width 0.1524)
				(type default)
			)
			(layer "F.SilkS")
		)
		(fp_line
			(start 0.8636 0.8636)
			(end 0.8636 -0.8636)
			(stroke
				(width 0.1524)
				(type default)
			)
			(layer "F.SilkS")
		)
		(fp_poly
			(pts
				(xy -0.635 -0.635) (xy -0.635 0.635) (xy 0.635 0.635) (xy 0.635 -0.635)
			)
			(stroke
				(width 0)
				(type default)
			)
			(fill no)
			(layer "F.CrtYd")
		)
		(pad "1" smd rect
			(at 0 0)
			(size 1.27 1.27)
			(layers "F.Cu" "F.Mask" "F.Paste")
			(net "VDD_CORE_EN")
		)
	)
	(footprint ""
		(layer "F.Cu")
		(at 36.2712 41.656 90)
		(property "Reference" "R315"
			(at 0 0 90)
			(layer "F.SilkS")
			(hide yes)
			(effects
				(font
					(size 1.27 1.27)
				)
			)
		)
		(property "Value" "1.0K"
			(at -0.148158 1.3462 180)
			(unlocked yes)
			(layer "F.Fab")
			(hide yes)
			(effects
				(font
					(size 1.27 0.9652)
					(thickness 0.000001)
				)
				(justify left)
			)
		)
		(property "Device Type" "REST0025"
			(at -0.148158 1.3462 180)
			(unlocked yes)
			(layer "F.Fab")
			(hide yes)
			(effects
				(font
					(size 1.27 0.9652)
					(thickness 0.000001)
				)
				(justify left)
			)
		)
		(duplicate_pad_numbers_are_jumpers no)
		(fp_poly
			(pts
				(xy 0.635 1.0668) (xy 0.635 -1.0668) (xy -0.635 -1.0668) (xy -0.635 1.0668)
			)
			(stroke
				(width 0)
				(type default)
			)
			(fill no)
			(layer "F.CrtYd")
		)
		(fp_line
			(start 0.254 -0.508)
			(end 0.254 0.508)
			(stroke
				(width 0.0254)
				(type default)
			)
			(layer "F.Fab")
		)
		(fp_line
			(start -0.254 -0.508)
			(end 0.254 -0.508)
			(stroke
				(width 0.0254)
				(type default)
			)
			(layer "F.Fab")
		)
		(fp_line
			(start 0.254 0.508)
			(end -0.254 0.508)
			(stroke
				(width 0.0254)
				(type default)
			)
			(layer "F.Fab")
		)
		(fp_line
			(start -0.254 0.508)
			(end -0.254 -0.508)
			(stroke
				(width 0.0254)
				(type default)
			)
			(layer "F.Fab")
		)
		(pad "1" smd rect
			(at 0 -0.4191 90)
			(size 0.508 0.5334)
			(layers "F.Cu" "F.Mask" "F.Paste")
			(net "_SW2")
		)
		(pad "2" smd rect
			(at 0 0.4191 90)
			(size 0.508 0.5334)
			(layers "F.Cu" "F.Mask" "F.Paste")
			(net "NFP_VDD_CORE_ISEN2_P")
		)
		(zone
			(layer "F.Cu")
			(hatch none 0.5)
			(connect_pads
				(clearance 0)
			)
			(min_thickness 0.25)
			(keepout
				(tracks not_allowed)
				(vias allowed)
				(pads allowed)
				(copperpour not_allowed)
				(footprints allowed)
			)
			(placement
				(enabled no)
				(sheetname "")
			)
			(fill
				(thermal_gap 0.5)
				(thermal_bridge_width 0.5)
				(island_removal_mode 0)
			)
			(polygon
				(pts
					(xy 36.2458 41.6306) (xy 36.2966 41.6306) (xy 36.2966 41.6814) (xy 36.2458 41.6814)
				)
			)
		)
	)
	(footprint ""
		(layer "F.Cu")
		(at 76.251003 22.174073)
		(property "Reference" "R363"
			(at 0.991667 1.447927 90)
			(unlocked yes)
			(layer "F.SilkS")
			(effects
				(font
					(size 0.7874 0.5842)
					(thickness 0.127)
				)
				(justify left)
			)
		)
		(property "Value" "100"
			(at -0.148158 1.3462 90)
			(unlocked yes)
			(layer "F.Fab")
			(hide yes)
			(effects
				(font
					(size 1.27 0.9652)
					(thickness 0.000001)
				)
				(justify left)
			)
		)
		(property "Device Type" "REST4030"
			(at -0.148158 1.3462 90)
			(unlocked yes)
			(layer "F.Fab")
			(hide yes)
			(effects
				(font
					(size 1.27 0.9652)
					(thickness 0.000001)
				)
				(justify left)
			)
		)
		(duplicate_pad_numbers_are_jumpers no)
		(fp_poly
			(pts
				(xy 0.635 1.0668) (xy 0.635 -1.0668) (xy -0.635 -1.0668) (xy -0.635 1.0668)
			)
			(stroke
				(width 0)
				(type default)
			)
			(fill no)
			(layer "F.CrtYd")
		)
		(fp_line
			(start -0.254 -0.508)
			(end 0.254 -0.508)
			(stroke
				(width 0.0254)
				(type default)
			)
			(layer "F.Fab")
		)
		(fp_line
			(start -0.254 0.508)
			(end -0.254 -0.508)
			(stroke
				(width 0.0254)
				(type default)
			)
			(layer "F.Fab")
		)
		(fp_line
			(start 0.254 -0.508)
			(end 0.254 0.508)
			(stroke
				(width 0.0254)
				(type default)
			)
			(layer "F.Fab")
		)
		(fp_line
			(start 0.254 0.508)
			(end -0.254 0.508)
			(stroke
				(width 0.0254)
				(type default)
			)
			(layer "F.Fab")
		)
		(pad "1" smd rect
			(at 0 -0.4191)
			(size 0.508 0.5334)
			(layers "F.Cu" "F.Mask" "F.Paste")
			(net "GND")
		)
		(pad "2" smd rect
			(at 0 0.4191)
			(size 0.508 0.5334)
			(layers "F.Cu" "F.Mask" "F.Paste")
			(net "DDR0_32A_VREF1B")
		)
		(zone
			(layer "F.Cu")
			(hatch none 0.5)
			(connect_pads
				(clearance 0)
			)
			(min_thickness 0.25)
			(keepout
				(tracks not_allowed)
				(vias allowed)
				(pads allowed)
				(copperpour not_allowed)
				(footprints allowed)
			)
			(placement
				(enabled no)
				(sheetname "")
			)
			(fill
				(thermal_gap 0.5)
				(thermal_bridge_width 0.5)
				(island_removal_mode 0)
			)
			(polygon
				(pts
					(xy 76.276403 22.148673) (xy 76.276403 22.199473) (xy 76.225603 22.199473) (xy 76.225603 22.148673)
				)
			)
		)
	)
	(footprint ""
		(layer "F.Cu")
		(at 82.423 37.973)
		(property "Reference" "R318"
			(at 0 0 0)
			(layer "F.SilkS")
			(hide yes)
			(effects
				(font
					(size 1.27 1.27)
				)
			)
		)
		(property "Value" "1.0K"
			(at -0.148158 1.3462 90)
			(unlocked yes)
			(layer "F.Fab")
			(hide yes)
			(effects
				(font
					(size 1.27 0.9652)
					(thickness 0.000001)
				)
				(justify left)
			)
		)
		(property "Device Type" "REST0025"
			(at -0.148158 1.3462 90)
			(unlocked yes)
			(layer "F.Fab")
			(hide yes)
			(effects
				(font
					(size 1.27 0.9652)
					(thickness 0.000001)
				)
				(justify left)
			)
		)
		(duplicate_pad_numbers_are_jumpers no)
		(fp_poly
			(pts
				(xy 0.635 1.0668) (xy 0.635 -1.0668) (xy -0.635 -1.0668) (xy -0.635 1.0668)
			)
			(stroke
				(width 0)
				(type default)
			)
			(fill no)
			(layer "F.CrtYd")
		)
		(fp_line
			(start -0.254 -0.508)
			(end 0.254 -0.508)
			(stroke
				(width 0.0254)
				(type default)
			)
			(layer "F.Fab")
		)
		(fp_line
			(start -0.254 0.508)
			(end -0.254 -0.508)
			(stroke
				(width 0.0254)
				(type default)
			)
			(layer "F.Fab")
		)
		(fp_line
			(start 0.254 -0.508)
			(end 0.254 0.508)
			(stroke
				(width 0.0254)
				(type default)
			)
			(layer "F.Fab")
		)
		(fp_line
			(start 0.254 0.508)
			(end -0.254 0.508)
			(stroke
				(width 0.0254)
				(type default)
			)
			(layer "F.Fab")
		)
		(pad "1" smd rect
			(at 0 -0.4191)
			(size 0.508 0.5334)
			(layers "F.Cu" "F.Mask" "F.Paste")
			(net "GND")
		)
		(pad "2" smd rect
			(at 0 0.4191)
			(size 0.508 0.5334)
			(layers "F.Cu" "F.Mask" "F.Paste")
			(net "11N2138")
		)
		(zone
			(layer "F.Cu")
			(hatch none 0.5)
			(connect_pads
				(clearance 0)
			)
			(min_thickness 0.25)
			(keepout
				(tracks not_allowed)
				(vias allowed)
				(pads allowed)
				(copperpour not_allowed)
				(footprints allowed)
			)
			(placement
				(enabled no)
				(sheetname "")
			)
			(fill
				(thermal_gap 0.5)
				(thermal_bridge_width 0.5)
				(island_removal_mode 0)
			)
			(polygon
				(pts
					(xy 82.4484 37.9476) (xy 82.4484 37.9984) (xy 82.3976 37.9984) (xy 82.3976 37.9476)
				)
			)
		)
	)
	(footprint ""
		(layer "F.Cu")
		(at 78.994 5.715 90)
		(property "Reference" "C71"
			(at -0.28067 0.635 0)
			(unlocked yes)
			(layer "F.SilkS")
			(effects
				(font
					(size 0.7874 0.5842)
					(thickness 0.127)
				)
				(justify left)
			)
		)
		(property "Value" "8.2PF"
			(at -0.091846 0.2921 180)
			(unlocked yes)
			(layer "F.Fab")
			(hide yes)
			(effects
				(font
					(size 0.7874 0.5842)
					(thickness 0.2032)
				)
				(justify left)
			)
		)
		(property "Device Type" "CAPC0004"
			(at -0.091846 0.2921 180)
			(unlocked yes)
			(layer "F.Fab")
			(hide yes)
			(effects
				(font
					(size 0.7874 0.5842)
					(thickness 0.2032)
				)
				(justify left)
			)
		)
		(duplicate_pad_numbers_are_jumpers no)
		(fp_poly
			(pts
				(xy 0.635 1.0668) (xy 0.635 -1.0668) (xy -0.635 -1.0668) (xy -0.635 1.0668)
			)
			(stroke
				(width 0)
				(type default)
			)
			(fill no)
			(layer "F.CrtYd")
		)
		(fp_line
			(start 0.254 -0.508)
			(end 0.254 0.508)
			(stroke
				(width 0.0254)
				(type default)
			)
			(layer "F.Fab")
		)
		(fp_line
			(start -0.254 -0.508)
			(end 0.254 -0.508)
			(stroke
				(width 0.0254)
				(type default)
			)
			(layer "F.Fab")
		)
		(fp_line
			(start 0.254 0.508)
			(end -0.254 0.508)
			(stroke
				(width 0.0254)
				(type default)
			)
			(layer "F.Fab")
		)
		(fp_line
			(start -0.254 0.508)
			(end -0.254 -0.508)
			(stroke
				(width 0.0254)
				(type default)
			)
			(layer "F.Fab")
		)
		(pad "1" smd rect
			(at 0 -0.4191 90)
			(size 0.508 0.5334)
			(layers "F.Cu" "F.Mask" "F.Paste")
			(net "DDR0_32A_CK0_P")
		)
		(pad "2" smd rect
			(at 0 0.4191 90)
			(size 0.508 0.5334)
			(layers "F.Cu" "F.Mask" "F.Paste")
			(net "DDR0_32A_CK0_N")
		)
		(zone
			(layer "F.Cu")
			(hatch none 0.5)
			(connect_pads
				(clearance 0)
			)
			(min_thickness 0.25)
			(keepout
				(tracks not_allowed)
				(vias allowed)
				(pads allowed)
				(copperpour not_allowed)
				(footprints allowed)
			)
			(placement
				(enabled no)
				(sheetname "")
			)
			(fill
				(thermal_gap 0.5)
				(thermal_bridge_width 0.5)
				(island_removal_mode 0)
			)
			(polygon
				(pts
					(xy 78.9686 5.6896) (xy 79.0194 5.6896) (xy 79.0194 5.7404) (xy 78.9686 5.7404)
				)
			)
		)
	)
	(footprint ""
		(layer "F.Cu")
		(at 7.366 46.228)
		(property "Reference" "TP46"
			(at 1.397 1.42367 0)
			(unlocked yes)
			(layer "F.SilkS")
			(effects
				(font
					(size 0.7874 0.5842)
					(thickness 0.127)
				)
				(justify left)
			)
		)
		(property "Value" "*"
			(at -0.4826 -0.14732 0)
			(unlocked yes)
			(layer "F.Fab")
			(hide yes)
			(effects
				(font
					(size 1.27 0.9652)
					(thickness 0.000001)
				)
				(justify left)
			)
		)
		(property "Device Type" "TP_SMALL"
			(at -0.4826 -0.14732 0)
			(unlocked yes)
			(layer "F.Fab")
			(hide yes)
			(effects
				(font
					(size 1.27 0.9652)
					(thickness 0.000001)
				)
				(justify left)
			)
		)
		(duplicate_pad_numbers_are_jumpers no)
		(fp_line
			(start -0.8636 -0.8636)
			(end -0.8636 0.8636)
			(stroke
				(width 0.1524)
				(type default)
			)
			(layer "F.SilkS")
		)
		(fp_line
			(start -0.8636 0.8636)
			(end 0.8636 0.8636)
			(stroke
				(width 0.1524)
				(type default)
			)
			(layer "F.SilkS")
		)
		(fp_line
			(start 0.8636 -0.8636)
			(end -0.8636 -0.8636)
			(stroke
				(width 0.1524)
				(type default)
			)
			(layer "F.SilkS")
		)
		(fp_line
			(start 0.8636 0.8636)
			(end 0.8636 -0.8636)
			(stroke
				(width 0.1524)
				(type default)
			)
			(layer "F.SilkS")
		)
		(fp_poly
			(pts
				(xy -0.635 -0.635) (xy -0.635 0.635) (xy 0.635 0.635) (xy 0.635 -0.635)
			)
			(stroke
				(width 0)
				(type default)
			)
			(fill no)
			(layer "F.CrtYd")
		)
		(pad "1" smd rect
			(at 0 0)
			(size 1.27 1.27)
			(layers "F.Cu" "F.Mask" "F.Paste")
			(net "VDD_1.5V")
		)
	)
	(footprint ""
		(layer "F.Cu")
		(at 74.651006 25.813004)
		(property "Reference" "V_A-CB2"
			(at 0 0 0)
			(layer "F.SilkS")
			(hide yes)
			(effects
				(font
					(size 1.27 1.27)
				)
			)
		)
		(property "Value" ""
			(at 0 0 0)
			(layer "F.Fab")
			(effects
				(font
					(size 1.27 1.27)
				)
			)
		)
		(duplicate_pad_numbers_are_jumpers no)
		(pad "1" thru_hole circle
			(at 0 0)
			(size 0.762 0.762)
			(drill 0.20574)
			(layers "*.Cu" "*.Mask")
			(remove_unused_layers no)
			(net "DDR0_32A_CB2")
			(clearance 0.127)
			(thermal_gap 0.127)
			(padstack
				(mode front_inner_back)
				(layer "Inner"
					(shape circle)
					(size 0.4572 0.4572)
					(clearance 0.1143)
				)
				(layer "B.Cu"
					(shape circle)
					(size 0.4572 0.4572)
					(clearance 0.1143)
				)
			)
		)
	)
)
